# T6G (Grand Teton) — schematic netlist excerpt (pin names and nets, part order shuffled) for the footprints in the layout excerpt that follows; sources: Cadence DE-HDL packaged netlist, KiCad conversion of 04192023_DAF0TMB3IC0_F0TG_MB_C_brd_V02_OCP.brd

C6117  Q_CAP  0.1UF 25V 10% X7R  pkg 0402  page 179 : A = P1V2_CPU0_USB2_DVDD12 ; B = GND
C136  Q_CAP  0.1UF 25V 10% X7R  pkg 0402  page 98 : A = P3V3_AUX ; B = GND
C6735  Q_CAP_DIFFBUS  DIFF BUS_0.22UF 6.3V 20% X6S  pkg C0201  page 352 : \1\ = P5E_CPU1_P3_TX_BUF_C_DP<5> ; \2\ = P5E_CPU1_P3_TX_BUF_DP<5>

(kicad_pcb
	(version 20260206)
	(generator "pcbnew")
	(generator_version "10.0")
	(general
		(thickness 1.6)
		(legacy_teardrops no)
	)
	(paper "A4")
	(title_block
		(title "04192023_DAF0TMB3IC0_F0TG_MB_C_brd_V02_OCP.brd")
		(comment 1 "Grand Teton / footprints 5454-5456 of 8354")
	)
	(layers
		(0 "F.Cu" signal "TOP")
		(4 "In1.Cu" signal "GND")
		(6 "In2.Cu" signal "IN1")
		(8 "In3.Cu" signal "GND1")
		(10 "In4.Cu" signal "IN2")
		(12 "In5.Cu" signal "GND2")
		(14 "In6.Cu" signal "IN3")
		(16 "In7.Cu" signal "GND3")
		(18 "In8.Cu" signal "VCC")
		(20 "In9.Cu" signal "VCC1")
		(22 "In10.Cu" signal "GND4")
		(24 "In11.Cu" signal "IN4")
		(26 "In12.Cu" signal "GND5")
		(28 "In13.Cu" signal "IN5")
		(30 "In14.Cu" signal "GND6")
		(32 "In15.Cu" signal "IN6")
		(34 "In16.Cu" signal "GND7")
		(2 "B.Cu" signal "BOTTOM")
		(9 "F.Adhes" user "F.Adhesive")
		(11 "B.Adhes" user "B.Adhesive")
		(13 "F.Paste" user "Package Geometry/Pastemask Top")
		(15 "B.Paste" user "Package Geometry/Pastemask Bottom")
		(5 "F.SilkS" user "Ref Des/Silkscreen Top")
		(7 "B.SilkS" user "Ref Des/Silkscreen Bottom")
		(1 "F.Mask" user "Board Geometry/Soldermask Top")
		(3 "B.Mask" user "Board Geometry/Soldermask Bottom")
		(17 "Dwgs.User" user "User.Drawings")
		(19 "Cmts.User" user "User.Comments")
		(21 "Eco1.User" user "User.Eco1")
		(23 "Eco2.User" user "User.Eco2")
		(25 "Edge.Cuts" user "Board Geometry/Outline")
		(27 "Margin" user)
		(31 "F.CrtYd" user "Package Geometry/Place Bound Top")
		(29 "B.CrtYd" user "Package Geometry/Place Bound Bottom")
		(35 "F.Fab" user "Ref Des/Assembly Top")
		(33 "B.Fab" user "Ref Des/Assembly Bottom")
	)
	(footprint ""
		(layer "B.Cu")
		(at 59.401202 -193.996564)
		(property "Reference" "C136"
			(at 0 0 0)
			(layer "B.SilkS")
			(hide yes)
			(effects
				(font
					(size 1.27 1.27)
				)
				(justify mirror)
			)
		)
		(property "Value" ""
			(at 0 0 0)
			(layer "B.Fab")
			(effects
				(font
					(size 1.27 1.27)
				)
				(justify mirror)
			)
		)
		(duplicate_pad_numbers_are_jumpers no)
		(fp_line
			(start -0.7874 -0.4064)
			(end -0.7874 0.4064)
			(stroke
				(width 0.1524)
				(type default)
			)
			(layer "B.SilkS")
		)
		(fp_line
			(start -0.7874 0.4064)
			(end 0.7874 0.4064)
			(stroke
				(width 0.1524)
				(type default)
			)
			(layer "B.SilkS")
		)
		(fp_line
			(start 0.7874 -0.4064)
			(end -0.7874 -0.4064)
			(stroke
				(width 0.1524)
				(type default)
			)
			(layer "B.SilkS")
		)
		(fp_line
			(start 0.7874 0.4064)
			(end 0.7874 -0.4064)
			(stroke
				(width 0.1524)
				(type default)
			)
			(layer "B.SilkS")
		)
		(fp_line
			(start -0.67945 -0.3048)
			(end -0.67945 0.3048)
			(stroke
				(width 0.1)
				(type default)
			)
			(layer "B.Fab")
		)
		(fp_line
			(start -0.67945 0.3048)
			(end -0.120396 0.3048)
			(stroke
				(width 0.1)
				(type default)
			)
			(layer "B.Fab")
		)
		(fp_line
			(start -0.12065 -0.3048)
			(end -0.67945 -0.3048)
			(stroke
				(width 0.1)
				(type default)
			)
			(layer "B.Fab")
		)
		(fp_line
			(start -0.12065 -0.2794)
			(end -0.12065 -0.3048)
			(stroke
				(width 0.1)
				(type default)
			)
			(layer "B.Fab")
		)
		(fp_line
			(start -0.120396 0.2794)
			(end 0.12065 0.2794)
			(stroke
				(width 0.1)
				(type default)
			)
			(layer "B.Fab")
		)
		(fp_line
			(start -0.120396 0.3048)
			(end -0.120396 0.2794)
			(stroke
				(width 0.1)
				(type default)
			)
			(layer "B.Fab")
		)
		(fp_line
			(start 0.12065 -0.305054)
			(end 0.12065 -0.2794)
			(stroke
				(width 0.1)
				(type default)
			)
			(layer "B.Fab")
		)
		(fp_line
			(start 0.12065 -0.2794)
			(end -0.12065 -0.2794)
			(stroke
				(width 0.1)
				(type default)
			)
			(layer "B.Fab")
		)
		(fp_line
			(start 0.12065 0.2794)
			(end 0.12065 0.3048)
			(stroke
				(width 0.1)
				(type default)
			)
			(layer "B.Fab")
		)
		(fp_line
			(start 0.12065 0.3048)
			(end 0.67945 0.3048)
			(stroke
				(width 0.1)
				(type default)
			)
			(layer "B.Fab")
		)
		(fp_line
			(start 0.67945 -0.305054)
			(end 0.12065 -0.305054)
			(stroke
				(width 0.1)
				(type default)
			)
			(layer "B.Fab")
		)
		(fp_line
			(start 0.67945 0.3048)
			(end 0.67945 -0.305054)
			(stroke
				(width 0.1)
				(type default)
			)
			(layer "B.Fab")
		)
		(pad "1" smd circle
			(at 0.40005 0 180)
			(size 0 0)
			(layers "B.Cu" "B.Mask" "B.Paste")
			(net "P3V3_AUX")
		)
		(pad "2" smd circle
			(at -0.40005 0 180)
			(size 0 0)
			(layers "B.Cu" "B.Mask" "B.Paste")
			(net "GND")
		)
	)
	(footprint ""
		(layer "B.Cu")
		(at 117.102128 -27.441906 180)
		(property "Reference" "C6117"
			(at 0 0 0)
			(layer "B.SilkS")
			(hide yes)
			(effects
				(font
					(size 1.27 1.27)
				)
				(justify mirror)
			)
		)
		(property "Value" ""
			(at 0 0 0)
			(layer "B.Fab")
			(effects
				(font
					(size 1.27 1.27)
				)
				(justify mirror)
			)
		)
		(duplicate_pad_numbers_are_jumpers no)
		(fp_line
			(start 0.7874 0.4064)
			(end 0.7874 -0.4064)
			(stroke
				(width 0.1524)
				(type default)
			)
			(layer "B.SilkS")
		)
		(fp_line
			(start 0.7874 -0.4064)
			(end -0.7874 -0.4064)
			(stroke
				(width 0.1524)
				(type default)
			)
			(layer "B.SilkS")
		)
		(fp_line
			(start -0.7874 0.4064)
			(end 0.7874 0.4064)
			(stroke
				(width 0.1524)
				(type default)
			)
			(layer "B.SilkS")
		)
		(fp_line
			(start -0.7874 -0.4064)
			(end -0.7874 0.4064)
			(stroke
				(width 0.1524)
				(type default)
			)
			(layer "B.SilkS")
		)
		(fp_line
			(start 0.67945 0.3048)
			(end 0.67945 -0.305054)
			(stroke
				(width 0.1)
				(type default)
			)
			(layer "B.Fab")
		)
		(fp_line
			(start 0.67945 -0.305054)
			(end 0.12065 -0.305054)
			(stroke
				(width 0.1)
				(type default)
			)
			(layer "B.Fab")
		)
		(fp_line
			(start 0.12065 0.3048)
			(end 0.67945 0.3048)
			(stroke
				(width 0.1)
				(type default)
			)
			(layer "B.Fab")
		)
		(fp_line
			(start 0.12065 0.2794)
			(end 0.12065 0.3048)
			(stroke
				(width 0.1)
				(type default)
			)
			(layer "B.Fab")
		)
		(fp_line
			(start 0.12065 -0.2794)
			(end -0.12065 -0.2794)
			(stroke
				(width 0.1)
				(type default)
			)
			(layer "B.Fab")
		)
		(fp_line
			(start 0.12065 -0.305054)
			(end 0.12065 -0.2794)
			(stroke
				(width 0.1)
				(type default)
			)
			(layer "B.Fab")
		)
		(fp_line
			(start -0.120396 0.3048)
			(end -0.120396 0.2794)
			(stroke
				(width 0.1)
				(type default)
			)
			(layer "B.Fab")
		)
		(fp_line
			(start -0.120396 0.2794)
			(end 0.12065 0.2794)
			(stroke
				(width 0.1)
				(type default)
			)
			(layer "B.Fab")
		)
		(fp_line
			(start -0.12065 -0.2794)
			(end -0.12065 -0.3048)
			(stroke
				(width 0.1)
				(type default)
			)
			(layer "B.Fab")
		)
		(fp_line
			(start -0.12065 -0.3048)
			(end -0.67945 -0.3048)
			(stroke
				(width 0.1)
				(type default)
			)
			(layer "B.Fab")
		)
		(fp_line
			(start -0.67945 0.3048)
			(end -0.120396 0.3048)
			(stroke
				(width 0.1)
				(type default)
			)
			(layer "B.Fab")
		)
		(fp_line
			(start -0.67945 -0.3048)
			(end -0.67945 0.3048)
			(stroke
				(width 0.1)
				(type default)
			)
			(layer "B.Fab")
		)
		(pad "1" smd circle
			(at 0.40005 0)
			(size 0 0)
			(layers "B.Cu" "B.Mask" "B.Paste")
			(net "P1V2_CPU0_USB2_DVDD12")
		)
		(pad "2" smd circle
			(at -0.40005 0)
			(size 0 0)
			(layers "B.Cu" "B.Mask" "B.Paste")
			(net "GND")
		)
	)
	(footprint ""
		(layer "B.Cu")
		(at 132.630926 -408.517344 90)
		(property "Reference" "C6735"
			(at 0 0 90)
			(layer "B.SilkS")
			(hide yes)
			(effects
				(font
					(size 1.27 1.27)
				)
				(justify mirror)
			)
		)
		(property "Value" ""
			(at 0 0 90)
			(layer "B.Fab")
			(effects
				(font
					(size 1.27 1.27)
				)
				(justify mirror)
			)
		)
		(duplicate_pad_numbers_are_jumpers no)
		(fp_line
			(start 0.299974 -0.150114)
			(end -0.299974 -0.150114)
			(stroke
				(width 0.1)
				(type default)
			)
			(layer "B.Fab")
		)
		(fp_line
			(start -0.299974 -0.150114)
			(end -0.299974 0.150114)
			(stroke
				(width 0.1)
				(type default)
			)
			(layer "B.Fab")
		)
		(fp_line
			(start 0.299974 0.150114)
			(end 0.299974 -0.150114)
			(stroke
				(width 0.1)
				(type default)
			)
			(layer "B.Fab")
		)
		(fp_line
			(start -0.299974 0.150114)
			(end 0.299974 0.150114)
			(stroke
				(width 0.1)
				(type default)
			)
			(layer "B.Fab")
		)
		(pad "1" smd rect
			(at 0.2667 0 270)
			(size 0.3048 0.381)
			(layers "B.Cu" "B.Mask" "B.Paste")
			(net "P5E_CPU1_P3_TX_BUF_C_DP<5>")
		)
		(pad "2" smd rect
			(at -0.2667 0 270)
			(size 0.3048 0.381)
			(layers "B.Cu" "B.Mask" "B.Paste")
			(net "P5E_CPU1_P3_TX_BUF_DP<5>")
		)
	)
)
